(kicad_pcb
	(version 20260206)
	(generator "pcbnew")
	(generator_version "10.0")
	(general
		(thickness 1.6)
		(legacy_teardrops no)
	)
	(paper "A4")
	(title_block
		(title "panther-plus-userver — 13130-1b_20150205.brd")
		(comment 1 "Honey Badger (Wiwynn) / footprint 282 of 1509 (U13), pads 1056-1173 of 1283")
	)
	(layers
		(0 "F.Cu" signal "TOP")
		(4 "In1.Cu" signal "L2")
		(6 "In2.Cu" signal "L3")
		(8 "In3.Cu" signal "L4")
		(10 "In4.Cu" signal "L5")
		(12 "In5.Cu" signal "L6")
		(14 "In6.Cu" signal "L7")
		(16 "In7.Cu" signal "L8")
		(18 "In8.Cu" signal "L9")
		(20 "In9.Cu" signal "L10")
		(22 "In10.Cu" signal "L11")
		(2 "B.Cu" signal "BOTTOM")
		(9 "F.Adhes" user "F.Adhesive")
		(11 "B.Adhes" user "B.Adhesive")
		(13 "F.Paste" user "Package Geometry/Pastemask Top")
		(15 "B.Paste" user "Package Geometry/Pastemask Bottom")
		(5 "F.SilkS" user "Ref Des/Silkscreen Top")
		(7 "B.SilkS" user "Ref Des/Silkscreen Bottom")
		(1 "F.Mask" user "Board Geometry/Soldermask Top")
		(3 "B.Mask" user "Board Geometry/Soldermask Bottom")
		(17 "Dwgs.User" user "User.Drawings")
		(19 "Cmts.User" user "User.Comments")
		(21 "Eco1.User" user "User.Eco1")
		(23 "Eco2.User" user "User.Eco2")
		(25 "Edge.Cuts" user "Board Geometry/Outline")
		(27 "Margin" user)
		(31 "F.CrtYd" user "Package Geometry/Place Bound Top")
		(29 "B.CrtYd" user "Package Geometry/Place Bound Bottom")
		(35 "F.Fab" user "Ref Des/Assembly Top")
		(33 "B.Fab" user "Ref Des/Assembly Bottom")
	)
	(footprint ""
		(layer "F.Cu")
		(at 95.849948 -39.200074 180)
		(property "Reference" "U13"
			(at 0 0 180)
			(layer "F.SilkS")
			(hide yes)
			(effects
				(font
					(size 1.27 1.27)
				)
			)
		)
		(property "Value" "AVOTON-GP"
			(at -25.0317 -2.4892 180)
			(unlocked yes)
			(layer "F.Fab")
			(hide yes)
			(effects
				(font
					(size 1.016 1.016)
					(thickness 0.1524)
				)
			)
		)
		(property "Device Type" "BGA1283M3428-3H197"
			(at -25.0317 -4.0132 180)
			(unlocked yes)
			(layer "F.Fab")
			(hide yes)
			(effects
				(font
					(size 1.016 1.016)
					(thickness 0.1524)
				)
			)
		)
		(duplicate_pad_numbers_are_jumpers no)
		(pad "L37" smd circle
			(at 1.51638 -8.44042 180)
			(size 0.3048 0.3048)
			(layers "F.Cu" "F.Mask" "F.Paste")
			(net "CLK_100M_CPU_HFHPLL_DP")
		)
		(pad "L38" smd circle
			(at 2.21742 -8.44042 180)
			(size 0.3048 0.3048)
			(layers "F.Cu" "F.Mask" "F.Paste")
			(net "TP_CPU_RSVD16")
		)
		(pad "L41" smd circle
			(at 3.50266 -8.05942 180)
			(size 0.3048 0.3048)
			(layers "F.Cu" "F.Mask" "F.Paste")
			(net "P1V0")
		)
		(pad "L42" smd circle
			(at 4.2037 -8.05942 180)
			(size 0.3048 0.3048)
			(layers "F.Cu" "F.Mask" "F.Paste")
			(net "P1V0")
		)
		(pad "L44" smd circle
			(at 5.48894 -8.44042 180)
			(size 0.3048 0.3048)
			(layers "F.Cu" "F.Mask" "F.Paste")
			(net "Net_1365")
		)
		(pad "L46" smd circle
			(at 6.18998 -8.44042 180)
			(size 0.3048 0.3048)
			(layers "F.Cu" "F.Mask" "F.Paste")
			(net "Net_275")
		)
		(pad "L48" smd circle
			(at 7.47522 -8.05942 180)
			(size 0.3048 0.3048)
			(layers "F.Cu" "F.Mask" "F.Paste")
			(net "GND")
		)
		(pad "L50" smd circle
			(at 8.17626 -8.05942 180)
			(size 0.3048 0.3048)
			(layers "F.Cu" "F.Mask" "F.Paste")
			(net "GND")
		)
		(pad "L52" smd circle
			(at 9.4615 -8.44042 180)
			(size 0.3048 0.3048)
			(layers "F.Cu" "F.Mask" "F.Paste")
			(net "SATA2_OBS_N")
		)
		(pad "L54" smd circle
			(at 10.16254 -8.44042 180)
			(size 0.3048 0.3048)
			(layers "F.Cu" "F.Mask" "F.Paste")
			(net "CLK_100M_SATA2_DN")
		)
		(pad "L57" smd circle
			(at 11.82116 -8.41502 180)
			(size 0.3048 0.3048)
			(layers "F.Cu" "F.Mask" "F.Paste")
			(net "CLK_100M_CPU_SATA3_DP")
		)
		(pad "L59" smd circle
			(at 12.58316 -8.41502 180)
			(size 0.3048 0.3048)
			(layers "F.Cu" "F.Mask" "F.Paste")
			(net "CLK_100M_CPU_SATA3_DN")
		)
		(pad "L60" smd circle
			(at 13.34516 -8.41502 180)
			(size 0.3048 0.3048)
			(layers "F.Cu" "F.Mask" "F.Paste")
			(net "GND")
		)
		(pad "L63" smd circle
			(at 14.7955 -8.44042 180)
			(size 0.3048 0.3048)
			(layers "F.Cu" "F.Mask" "F.Paste")
			(net "SATA3_RX_DP1")
		)
		(pad "L65" smd circle
			(at 15.75308 -8.38708 180)
			(size 0.3048 0.3048)
			(layers "F.Cu" "F.Mask" "F.Paste")
			(net "SATA3_RX_DN1")
		)
		(pad "M3" smd circle
			(at -15.24762 -7.71906 180)
			(size 0.3048 0.3048)
			(layers "F.Cu" "F.Mask" "F.Paste")
			(net "PV_VDDR")
		)
		(pad "M5" smd circle
			(at -14.01318 -7.68858 180)
			(size 0.3048 0.3048)
			(layers "F.Cu" "F.Mask" "F.Paste")
			(net "GND")
		)
		(pad "M21" smd circle
			(at -6.42874 -7.67842 180)
			(size 0.3048 0.3048)
			(layers "F.Cu" "F.Mask" "F.Paste")
			(net "M_B_MA4")
		)
		(pad "M22" smd circle
			(at -5.7277 -7.67842 180)
			(size 0.3048 0.3048)
			(layers "F.Cu" "F.Mask" "F.Paste")
			(net "M_B_MA9")
		)
		(pad "M29" smd circle
			(at -2.45618 -7.67842 180)
			(size 0.3048 0.3048)
			(layers "F.Cu" "F.Mask" "F.Paste")
			(net "M_B_DQS_DP3")
		)
		(pad "M30" smd circle
			(at -1.75514 -7.67842 180)
			(size 0.3048 0.3048)
			(layers "F.Cu" "F.Mask" "F.Paste")
			(net "M_B_DQ30")
		)
		(pad "M37" smd circle
			(at 1.51638 -7.67842 180)
			(size 0.3048 0.3048)
			(layers "F.Cu" "F.Mask" "F.Paste")
			(net "GND")
		)
		(pad "M38" smd circle
			(at 2.21742 -7.67842 180)
			(size 0.3048 0.3048)
			(layers "F.Cu" "F.Mask" "F.Paste")
			(net "GND")
		)
		(pad "M44" smd circle
			(at 5.48894 -7.67842 180)
			(size 0.3048 0.3048)
			(layers "F.Cu" "F.Mask" "F.Paste")
			(net "GND")
		)
		(pad "M46" smd circle
			(at 6.18998 -7.67842 180)
			(size 0.3048 0.3048)
			(layers "F.Cu" "F.Mask" "F.Paste")
			(net "GND")
		)
		(pad "M52" smd circle
			(at 9.4615 -7.67842 180)
			(size 0.3048 0.3048)
			(layers "F.Cu" "F.Mask" "F.Paste")
			(net "GND")
		)
		(pad "M54" smd circle
			(at 10.29716 -7.71398 180)
			(size 0.3048 0.3048)
			(layers "F.Cu" "F.Mask" "F.Paste")
			(net "GND")
		)
		(pad "M56" smd circle
			(at 11.05916 -7.71398 180)
			(size 0.3048 0.3048)
			(layers "F.Cu" "F.Mask" "F.Paste")
			(net "GND")
		)
		(pad "M57" smd circle
			(at 11.82116 -7.71398 180)
			(size 0.3048 0.3048)
			(layers "F.Cu" "F.Mask" "F.Paste")
			(net "GND")
		)
		(pad "M59" smd circle
			(at 12.58316 -7.71398 180)
			(size 0.3048 0.3048)
			(layers "F.Cu" "F.Mask" "F.Paste")
			(net "GND")
		)
		(pad "M60" smd circle
			(at 13.34516 -7.71398 180)
			(size 0.3048 0.3048)
			(layers "F.Cu" "F.Mask" "F.Paste")
			(net "GND")
		)
		(pad "M62" smd circle
			(at 14.08176 -7.89178 180)
			(size 0.3048 0.3048)
			(layers "F.Cu" "F.Mask" "F.Paste")
			(net "SATA3_RX_DP0")
		)
		(pad "M64" smd circle
			(at 15.24254 -7.90194 180)
			(size 0.3048 0.3048)
			(layers "F.Cu" "F.Mask" "F.Paste")
			(net "SATA3_RX_DN0")
		)
		(pad "M66" smd oval
			(at 16.24838 -7.6708 180)
			(size 0.3429 0.254)
			(layers "F.Cu" "F.Mask" "F.Paste")
			(net "GND")
		)
		(pad "N1" smd oval
			(at -16.24838 -7.46252 180)
			(size 0.3429 0.254)
			(layers "F.Cu" "F.Mask" "F.Paste")
			(net "GND")
		)
		(pad "N2" smd circle
			(at -15.64132 -7.11454 180)
			(size 0.3048 0.3048)
			(layers "F.Cu" "F.Mask" "F.Paste")
			(net "M_B_ODT1")
		)
		(pad "N4" smd circle
			(at -14.89964 -7.10692 180)
			(size 0.3048 0.3048)
			(layers "F.Cu" "F.Mask" "F.Paste")
			(net "M_B_CS_N1")
		)
		(pad "N5" smd circle
			(at -14.20368 -7.0104 180)
			(size 0.3048 0.3048)
			(layers "F.Cu" "F.Mask" "F.Paste")
			(net "GND")
		)
		(pad "N7" smd circle
			(at -13.34516 -7.47522 180)
			(size 0.3048 0.3048)
			(layers "F.Cu" "F.Mask" "F.Paste")
			(net "M_B_WE#")
		)
		(pad "N8" smd circle
			(at -12.58316 -7.47522 180)
			(size 0.3048 0.3048)
			(layers "F.Cu" "F.Mask" "F.Paste")
			(net "M_B_ODT2")
		)
		(pad "N10" smd circle
			(at -11.82116 -7.47522 180)
			(size 0.3048 0.3048)
			(layers "F.Cu" "F.Mask" "F.Paste")
			(net "GND")
		)
		(pad "N11" smd circle
			(at -11.05916 -7.47522 180)
			(size 0.3048 0.3048)
			(layers "F.Cu" "F.Mask" "F.Paste")
			(net "M_B_R_RESET#")
		)
		(pad "N13" smd circle
			(at -10.29716 -7.47522 180)
			(size 0.3048 0.3048)
			(layers "F.Cu" "F.Mask" "F.Paste")
			(net "PV_VDDR")
		)
		(pad "N14" smd circle
			(at -9.53516 -7.47522 180)
			(size 0.3048 0.3048)
			(layers "F.Cu" "F.Mask" "F.Paste")
			(net "PV_VDDR")
		)
		(pad "N17" smd circle
			(at -8.41502 -7.29742 180)
			(size 0.3048 0.3048)
			(layers "F.Cu" "F.Mask" "F.Paste")
			(net "PWRGD_DDR3_VCCA")
		)
		(pad "N18" smd circle
			(at -7.71398 -7.29742 180)
			(size 0.3048 0.3048)
			(layers "F.Cu" "F.Mask" "F.Paste")
			(net "M_B_BS0")
		)
		(pad "N25" smd circle
			(at -4.44246 -7.29742 180)
			(size 0.3048 0.3048)
			(layers "F.Cu" "F.Mask" "F.Paste")
			(net "M_B_CKE1")
		)
		(pad "N26" smd circle
			(at -3.74142 -7.29742 180)
			(size 0.3048 0.3048)
			(layers "F.Cu" "F.Mask" "F.Paste")
			(net "M_B_CKE0")
		)
		(pad "N32" smd circle
			(at -0.4699 -7.29742 180)
			(size 0.3048 0.3048)
			(layers "F.Cu" "F.Mask" "F.Paste")
			(net "M_B_DQ26")
		)
		(pad "N34" smd circle
			(at 0.23114 -7.29742 180)
			(size 0.3048 0.3048)
			(layers "F.Cu" "F.Mask" "F.Paste")
			(net "GND")
		)
		(pad "N41" smd circle
			(at 3.50266 -7.29742 180)
			(size 0.3048 0.3048)
			(layers "F.Cu" "F.Mask" "F.Paste")
			(net "P1V0")
		)
		(pad "N42" smd circle
			(at 4.2037 -7.29742 180)
			(size 0.3048 0.3048)
			(layers "F.Cu" "F.Mask" "F.Paste")
			(net "P1V0")
		)
		(pad "N48" smd circle
			(at 7.47522 -7.29742 180)
			(size 0.3048 0.3048)
			(layers "F.Cu" "F.Mask" "F.Paste")
			(net "GND")
		)
		(pad "N50" smd circle
			(at 8.17626 -7.29742 180)
			(size 0.3048 0.3048)
			(layers "F.Cu" "F.Mask" "F.Paste")
			(net "GND")
		)
		(pad "N62" smd circle
			(at 14.20368 -7.19836 180)
			(size 0.3048 0.3048)
			(layers "F.Cu" "F.Mask" "F.Paste")
			(net "GND")
		)
		(pad "N63" smd circle
			(at 14.89964 -7.2898 180)
			(size 0.3048 0.3048)
			(layers "F.Cu" "F.Mask" "F.Paste")
			(net "GND")
		)
		(pad "N65" smd circle
			(at 15.63878 -7.32028 180)
			(size 0.3048 0.3048)
			(layers "F.Cu" "F.Mask" "F.Paste")
			(net "GND")
		)
		(pad "P17" smd circle
			(at -8.41502 -6.53542 180)
			(size 0.3048 0.3048)
			(layers "F.Cu" "F.Mask" "F.Paste")
			(net "PV_VDDR")
		)
		(pad "P18" smd circle
			(at -7.71398 -6.53542 180)
			(size 0.3048 0.3048)
			(layers "F.Cu" "F.Mask" "F.Paste")
			(net "PV_VDDR")
		)
		(pad "P21" smd circle
			(at -6.42874 -6.91642 180)
			(size 0.3048 0.3048)
			(layers "F.Cu" "F.Mask" "F.Paste")
			(net "M_B_MA3")
		)
		(pad "P22" smd circle
			(at -5.7277 -6.91642 180)
			(size 0.3048 0.3048)
			(layers "F.Cu" "F.Mask" "F.Paste")
			(net "M_B_MA11")
		)
		(pad "P25" smd circle
			(at -4.44246 -6.53542 180)
			(size 0.3048 0.3048)
			(layers "F.Cu" "F.Mask" "F.Paste")
			(net "PV_VDDR")
		)
		(pad "P26" smd circle
			(at -3.74142 -6.53542 180)
			(size 0.3048 0.3048)
			(layers "F.Cu" "F.Mask" "F.Paste")
			(net "PV_VDDR")
		)
		(pad "P29" smd circle
			(at -2.45618 -6.91642 180)
			(size 0.3048 0.3048)
			(layers "F.Cu" "F.Mask" "F.Paste")
			(net "GND")
		)
		(pad "P30" smd circle
			(at -1.75514 -6.91642 180)
			(size 0.3048 0.3048)
			(layers "F.Cu" "F.Mask" "F.Paste")
			(net "M_B_DQ31")
		)
		(pad "P32" smd circle
			(at -0.4699 -6.53542 180)
			(size 0.3048 0.3048)
			(layers "F.Cu" "F.Mask" "F.Paste")
			(net "GND")
		)
		(pad "P34" smd circle
			(at 0.23114 -6.53542 180)
			(size 0.3048 0.3048)
			(layers "F.Cu" "F.Mask" "F.Paste")
			(net "GND")
		)
		(pad "P37" smd circle
			(at 1.51638 -6.91642 180)
			(size 0.3048 0.3048)
			(layers "F.Cu" "F.Mask" "F.Paste")
			(net "GND")
		)
		(pad "P38" smd circle
			(at 2.21742 -6.91642 180)
			(size 0.3048 0.3048)
			(layers "F.Cu" "F.Mask" "F.Paste")
			(net "TP_CPU_RSVD15")
		)
		(pad "P41" smd circle
			(at 3.50266 -6.53542 180)
			(size 0.3048 0.3048)
			(layers "F.Cu" "F.Mask" "F.Paste")
			(net "P1V0")
		)
		(pad "P42" smd circle
			(at 4.2037 -6.53542 180)
			(size 0.3048 0.3048)
			(layers "F.Cu" "F.Mask" "F.Paste")
			(net "P1V0")
		)
		(pad "P44" smd circle
			(at 5.48894 -6.91642 180)
			(size 0.3048 0.3048)
			(layers "F.Cu" "F.Mask" "F.Paste")
			(net "GND")
		)
		(pad "P46" smd circle
			(at 6.18998 -6.91642 180)
			(size 0.3048 0.3048)
			(layers "F.Cu" "F.Mask" "F.Paste")
			(net "BD_REV_0")
		)
		(pad "P48" smd circle
			(at 7.47522 -6.53542 180)
			(size 0.3048 0.3048)
			(layers "F.Cu" "F.Mask" "F.Paste")
			(net "NGFF_PRESENT#")
		)
		(pad "P50" smd circle
			(at 8.17626 -6.53542 180)
			(size 0.3048 0.3048)
			(layers "F.Cu" "F.Mask" "F.Paste")
			(net "GBE_SMBCLK")
		)
		(pad "R2" smd circle
			(at -15.63878 -6.18744 180)
			(size 0.3048 0.3048)
			(layers "F.Cu" "F.Mask" "F.Paste")
			(net "GND")
		)
		(pad "R4" smd circle
			(at -14.89964 -6.21792 180)
			(size 0.3048 0.3048)
			(layers "F.Cu" "F.Mask" "F.Paste")
			(net "GND")
		)
		(pad "R5" smd circle
			(at -14.20368 -6.3119 180)
			(size 0.3048 0.3048)
			(layers "F.Cu" "F.Mask" "F.Paste")
			(net "GND")
		)
		(pad "R8" smd circle
			(at -12.96416 -6.18998 180)
			(size 0.3048 0.3048)
			(layers "F.Cu" "F.Mask" "F.Paste")
			(net "M_B_DQ38")
		)
		(pad "R9" smd circle
			(at -12.20216 -6.18998 180)
			(size 0.3048 0.3048)
			(layers "F.Cu" "F.Mask" "F.Paste")
			(net "M_B_DQ34")
		)
		(pad "R11" smd circle
			(at -11.44016 -6.18998 180)
			(size 0.3048 0.3048)
			(layers "F.Cu" "F.Mask" "F.Paste")
			(net "M_B_DQ35")
		)
		(pad "R12" smd circle
			(at -10.67816 -6.18998 180)
			(size 0.3048 0.3048)
			(layers "F.Cu" "F.Mask" "F.Paste")
			(net "GND")
		)
		(pad "R14" smd circle
			(at -9.91616 -6.18998 180)
			(size 0.3048 0.3048)
			(layers "F.Cu" "F.Mask" "F.Paste")
			(net "M_B_DQ33")
		)
		(pad "R15" smd circle
			(at -9.15416 -6.18998 180)
			(size 0.3048 0.3048)
			(layers "F.Cu" "F.Mask" "F.Paste")
			(net "M_B_DQ32")
		)
		(pad "R21" smd circle
			(at -6.42874 -6.15442 180)
			(size 0.3048 0.3048)
			(layers "F.Cu" "F.Mask" "F.Paste")
			(net "PV_VDDR")
		)
		(pad "R22" smd circle
			(at -5.7277 -6.15442 180)
			(size 0.3048 0.3048)
			(layers "F.Cu" "F.Mask" "F.Paste")
			(net "PV_VDDR")
		)
		(pad "R29" smd circle
			(at -2.45618 -6.15442 180)
			(size 0.3048 0.3048)
			(layers "F.Cu" "F.Mask" "F.Paste")
			(net "M_B_VREF")
		)
		(pad "R30" smd circle
			(at -1.75514 -6.15442 180)
			(size 0.3048 0.3048)
			(layers "F.Cu" "F.Mask" "F.Paste")
			(net "GND")
		)
		(pad "R37" smd circle
			(at 1.51638 -6.15442 180)
			(size 0.3048 0.3048)
			(layers "F.Cu" "F.Mask" "F.Paste")
			(net "TP_CPU_RSVD14")
		)
		(pad "R38" smd circle
			(at 2.21742 -6.15442 180)
			(size 0.3048 0.3048)
			(layers "F.Cu" "F.Mask" "F.Paste")
			(net "GND")
		)
		(pad "R44" smd circle
			(at 5.48894 -6.15442 180)
			(size 0.3048 0.3048)
			(layers "F.Cu" "F.Mask" "F.Paste")
			(net "P1V0")
		)
		(pad "R46" smd circle
			(at 6.18998 -6.15442 180)
			(size 0.3048 0.3048)
			(layers "F.Cu" "F.Mask" "F.Paste")
			(net "P1V0")
		)
		(pad "R52" smd circle
			(at 9.15416 -6.42874 180)
			(size 0.3048 0.3048)
			(layers "F.Cu" "F.Mask" "F.Paste")
			(net "GND")
		)
		(pad "R53" smd circle
			(at 9.91616 -6.42874 180)
			(size 0.3048 0.3048)
			(layers "F.Cu" "F.Mask" "F.Paste")
			(net "SATA3_OBS_N")
		)
		(pad "R55" smd circle
			(at 10.67816 -6.42874 180)
			(size 0.3048 0.3048)
			(layers "F.Cu" "F.Mask" "F.Paste")
			(net "SATA3_OBS_P")
		)
		(pad "R56" smd circle
			(at 11.44016 -6.42874 180)
			(size 0.3048 0.3048)
			(layers "F.Cu" "F.Mask" "F.Paste")
			(net "GND")
		)
		(pad "R58" smd circle
			(at 12.20216 -6.42874 180)
			(size 0.3048 0.3048)
			(layers "F.Cu" "F.Mask" "F.Paste")
			(net "MSATA_PRESENT#")
		)
		(pad "R59" smd circle
			(at 12.96416 -6.42874 180)
			(size 0.3048 0.3048)
			(layers "F.Cu" "F.Mask" "F.Paste")
			(net "SPI_CS_GBE#")
		)
		(pad "R62" smd circle
			(at 14.20368 -6.49732 180)
			(size 0.3048 0.3048)
			(layers "F.Cu" "F.Mask" "F.Paste")
			(net "GND")
		)
		(pad "R63" smd circle
			(at 14.89964 -6.4008 180)
			(size 0.3048 0.3048)
			(layers "F.Cu" "F.Mask" "F.Paste")
			(net "SATA3_TX_DP1")
		)
		(pad "R65" smd circle
			(at 15.64132 -6.39572 180)
			(size 0.3048 0.3048)
			(layers "F.Cu" "F.Mask" "F.Paste")
			(net "SATA3_TX_DN1")
		)
		(pad "R66" smd oval
			(at 16.24838 -6.0452 180)
			(size 0.3429 0.254)
			(layers "F.Cu" "F.Mask" "F.Paste")
			(net "SATA3_TX_DP0")
		)
		(pad "T1" smd oval
			(at -16.24838 -5.83692 180)
			(size 0.3429 0.254)
			(layers "F.Cu" "F.Mask" "F.Paste")
			(net "M_B_DQ45")
		)
		(pad "T3" smd circle
			(at -15.24254 -5.60832 180)
			(size 0.3048 0.3048)
			(layers "F.Cu" "F.Mask" "F.Paste")
			(net "M_B_DQ44")
		)
		(pad "T5" smd circle
			(at -14.08176 -5.61848 180)
			(size 0.3048 0.3048)
			(layers "F.Cu" "F.Mask" "F.Paste")
			(net "GND")
		)
		(pad "T17" smd circle
			(at -8.41502 -5.77342 180)
			(size 0.3048 0.3048)
			(layers "F.Cu" "F.Mask" "F.Paste")
			(net "M_B_DQ36")
		)
		(pad "T18" smd circle
			(at -7.71398 -5.77342 180)
			(size 0.3048 0.3048)
			(layers "F.Cu" "F.Mask" "F.Paste")
			(net "GND")
		)
		(pad "T20" smd circle
			(at -6.70052 -5.50164 180)
			(size 0.3048 0.3048)
			(layers "F.Cu" "F.Mask" "F.Paste")
			(net "GND")
		)
		(pad "T21" smd circle
			(at -5.99948 -5.50164 180)
			(size 0.3048 0.3048)
			(layers "F.Cu" "F.Mask" "F.Paste")
			(net "GND")
		)
		(pad "T23" smd circle
			(at -5.20192 -5.50164 180)
			(size 0.381 0.381)
			(layers "F.Cu" "F.Mask" "F.Paste")
			(net "GND")
		)
		(pad "T25" smd circle
			(at -4.44246 -5.77342 180)
			(size 0.3048 0.3048)
			(layers "F.Cu" "F.Mask" "F.Paste")
			(net "M_B_CMDPU")
		)
		(pad "T26" smd circle
			(at -3.74142 -5.77342 180)
			(size 0.3048 0.3048)
			(layers "F.Cu" "F.Mask" "F.Paste")
			(net "M_B_DQPU")
		)
		(pad "T28" smd circle
			(at -2.79908 -5.50164 180)
			(size 0.381 0.381)
			(layers "F.Cu" "F.Mask" "F.Paste")
			(net "GND")
		)
		(pad "T29" smd circle
			(at -2.10058 -5.50164 180)
			(size 0.381 0.381)
			(layers "F.Cu" "F.Mask" "F.Paste")
			(net "GND")
		)
		(pad "T31" smd circle
			(at -1.19888 -5.50164 180)
			(size 0.381 0.381)
			(layers "F.Cu" "F.Mask" "F.Paste")
			(net "GND")
		)
		(pad "T32" smd circle
			(at -0.4699 -5.77342 180)
			(size 0.3048 0.3048)
			(layers "F.Cu" "F.Mask" "F.Paste")
			(net "M_B_ODTPU")
		)
		(pad "T34" smd circle
			(at 0.23114 -5.77342 180)
			(size 0.3048 0.3048)
			(layers "F.Cu" "F.Mask" "F.Paste")
			(net "GND")
		)
		(pad "T36" smd circle
			(at 1.19888 -5.50164 180)
			(size 0.381 0.381)
			(layers "F.Cu" "F.Mask" "F.Paste")
			(net "GND")
		)
	)
)
